(kicad_pcb
	(version 20260206)
	(generator "pcbnew")
	(generator_version "10.0")
	(general
		(thickness 1.6)
		(legacy_teardrops no)
	)
	(paper "A4")
	(title_block
		(title "Bryce Canyon_SCC_16316-1_OCP.brd")
		(comment 1 "Bryce Canyon / footprints 919-927 of 1561")
	)
	(layers
		(0 "F.Cu" signal "TOP")
		(4 "In1.Cu" signal "L2GND")
		(6 "In2.Cu" signal "L3")
		(8 "In3.Cu" signal "L4VCC")
		(10 "In4.Cu" signal "L5VCC")
		(12 "In5.Cu" signal "L6")
		(14 "In6.Cu" signal "L7GND")
		(2 "B.Cu" signal "BOTTOM")
		(9 "F.Adhes" user "F.Adhesive")
		(11 "B.Adhes" user "B.Adhesive")
		(13 "F.Paste" user "Package Geometry/Pastemask Top")
		(15 "B.Paste" user "Package Geometry/Pastemask Bottom")
		(5 "F.SilkS" user "Ref Des/Silkscreen Top")
		(7 "B.SilkS" user "Ref Des/Silkscreen Bottom")
		(1 "F.Mask" user "Board Geometry/Soldermask Top")
		(3 "B.Mask" user "Board Geometry/Soldermask Bottom")
		(17 "Dwgs.User" user "User.Drawings")
		(19 "Cmts.User" user "User.Comments")
		(21 "Eco1.User" user "User.Eco1")
		(23 "Eco2.User" user "User.Eco2")
		(25 "Edge.Cuts" user "Board Geometry/Outline")
		(27 "Margin" user)
		(31 "F.CrtYd" user "Package Geometry/Place Bound Top")
		(29 "B.CrtYd" user "Package Geometry/Place Bound Bottom")
		(35 "F.Fab" user "Ref Des/Assembly Top")
		(33 "B.Fab" user "Ref Des/Assembly Bottom")
	)
	(footprint ""
		(layer "B.Cu")
		(at 126.873 -39.4716 180)
		(property "Reference" "C50"
			(at 0 0 0)
			(layer "B.SilkS")
			(hide yes)
			(effects
				(font
					(size 1.27 1.27)
				)
				(justify mirror)
			)
		)
		(property "Value" "SCD01U16V1KX-GP"
			(at 2.8321 -1.7399 180)
			(unlocked yes)
			(layer "B.Fab")
			(hide yes)
			(effects
				(font
					(size 1.016 1.016)
					(thickness 0.1524)
				)
				(justify mirror)
			)
		)
		(property "Device Type" "C0201H13"
			(at 2.8321 -3.2639 180)
			(unlocked yes)
			(layer "B.Fab")
			(hide yes)
			(effects
				(font
					(size 1.016 1.016)
					(thickness 0.1524)
				)
				(justify mirror)
			)
		)
		(duplicate_pad_numbers_are_jumpers no)
		(fp_rect
			(start 0.2794 0.6477)
			(end -0.2794 -0.6477)
			(stroke
				(width 0)
				(type default)
			)
			(fill no)
			(layer "B.CrtYd")
		)
		(fp_rect
			(start 0.2794 0.6477)
			(end -0.2794 -0.6477)
			(stroke
				(width 0)
				(type default)
			)
			(fill no)
			(layer "B.Fab")
		)
		(pad "1" smd custom
			(at 0 -0.2794)
			(size 0.0762 0.0762)
			(layers "B.Cu" "B.Mask" "B.Paste")
			(net "PHY_DPB_TO_SCC_39_DN")
			(options
				(clearance outline)
				(anchor circle)
			)
			(primitives
				(gr_poly
					(pts
						(arc
							(start 0.1524 0.127)
							(mid 0.137521 0.162921)
							(end 0.1016 0.1778)
						)
						(arc
							(start -0.1016 0.1778)
							(mid -0.137521 0.162921)
							(end -0.1524 0.127)
						)
						(arc
							(start -0.1524 -0.127)
							(mid -0.137521 -0.162921)
							(end -0.1016 -0.1778)
						)
						(arc
							(start 0.1016 -0.1778)
							(mid 0.137521 -0.162921)
							(end 0.1524 -0.127)
						)
					)
					(width 0)
					(fill yes)
				)
			)
		)
		(pad "2" smd custom
			(at 0 0.2794)
			(size 0.0762 0.0762)
			(layers "B.Cu" "B.Mask" "B.Paste")
			(net "PHY_DPB_TO_SCC_C_39_DN")
			(options
				(clearance outline)
				(anchor circle)
			)
			(primitives
				(gr_poly
					(pts
						(arc
							(start 0.1524 0.127)
							(mid 0.137521 0.162921)
							(end 0.1016 0.1778)
						)
						(arc
							(start -0.1016 0.1778)
							(mid -0.137521 0.162921)
							(end -0.1524 0.127)
						)
						(arc
							(start -0.1524 -0.127)
							(mid -0.137521 -0.162921)
							(end -0.1016 -0.1778)
						)
						(arc
							(start 0.1016 -0.1778)
							(mid 0.137521 -0.162921)
							(end 0.1524 -0.127)
						)
					)
					(width 0)
					(fill yes)
				)
			)
		)
	)
	(footprint ""
		(layer "B.Cu")
		(at 184.0484 -24.6634)
		(property "Reference" "TP145"
			(at 0 0 0)
			(layer "B.SilkS")
			(hide yes)
			(effects
				(font
					(size 1.27 1.27)
				)
				(justify mirror)
			)
		)
		(property "Value" "TPAD28-2-GP"
			(at 0.0127 -1.6637 0)
			(unlocked yes)
			(layer "B.Fab")
			(hide yes)
			(effects
				(font
					(size 1.016 1.016)
					(thickness 0.1524)
				)
				(justify mirror)
			)
		)
		(property "Device Type" "TPAD28"
			(at 0.0127 -3.1877 0)
			(unlocked yes)
			(layer "B.Fab")
			(hide yes)
			(effects
				(font
					(size 1.016 1.016)
					(thickness 0.1524)
				)
				(justify mirror)
			)
		)
		(duplicate_pad_numbers_are_jumpers no)
		(fp_poly
			(pts
				(arc
					(start 0.3556 0)
					(mid -0.3556 0)
					(end 0.3556 0)
				)
			)
			(stroke
				(width 0)
				(type default)
			)
			(fill no)
			(layer "B.CrtYd")
		)
		(fp_poly
			(pts
				(arc
					(start 0.6096 0)
					(mid -0.6096 0)
					(end 0.6096 0)
				)
			)
			(stroke
				(width 0)
				(type default)
			)
			(fill no)
			(layer "B.Fab")
		)
		(pad "1" smd circle
			(at 0 0 180)
			(size 0.7112 0.7112)
			(layers "B.Cu" "B.Mask" "B.Paste")
			(net "SPARE1")
		)
	)
	(footprint ""
		(layer "B.Cu")
		(at 113.453672 -75.47737 90)
		(property "Reference" "C141"
			(at 0 0 90)
			(layer "B.SilkS")
			(hide yes)
			(effects
				(font
					(size 1.27 1.27)
				)
				(justify mirror)
			)
		)
		(property "Value" "SCD1U6D3V1KX-GP"
			(at 2.8321 -1.7399 90)
			(unlocked yes)
			(layer "B.Fab")
			(hide yes)
			(effects
				(font
					(size 1.016 1.016)
					(thickness 0.1524)
				)
				(justify mirror)
			)
		)
		(property "Device Type" "C0201H13"
			(at 2.8321 -3.2639 90)
			(unlocked yes)
			(layer "B.Fab")
			(hide yes)
			(effects
				(font
					(size 1.016 1.016)
					(thickness 0.1524)
				)
				(justify mirror)
			)
		)
		(duplicate_pad_numbers_are_jumpers no)
		(fp_rect
			(start 0.2794 0.6477)
			(end -0.2794 -0.6477)
			(stroke
				(width 0)
				(type default)
			)
			(fill no)
			(layer "B.CrtYd")
		)
		(fp_rect
			(start 0.2794 0.6477)
			(end -0.2794 -0.6477)
			(stroke
				(width 0)
				(type default)
			)
			(fill no)
			(layer "B.Fab")
		)
		(pad "1" smd custom
			(at 0 -0.2794 270)
			(size 0.0762 0.0762)
			(layers "B.Cu" "B.Mask" "B.Paste")
			(net "P1V8_E")
			(options
				(clearance outline)
				(anchor circle)
			)
			(primitives
				(gr_poly
					(pts
						(arc
							(start 0.1524 0.127)
							(mid 0.137521 0.162921)
							(end 0.1016 0.1778)
						)
						(arc
							(start -0.1016 0.1778)
							(mid -0.137521 0.162921)
							(end -0.1524 0.127)
						)
						(arc
							(start -0.1524 -0.127)
							(mid -0.137521 -0.162921)
							(end -0.1016 -0.1778)
						)
						(arc
							(start 0.1016 -0.1778)
							(mid 0.137521 -0.162921)
							(end 0.1524 -0.127)
						)
					)
					(width 0)
					(fill yes)
				)
			)
		)
		(pad "2" smd custom
			(at 0 0.2794 270)
			(size 0.0762 0.0762)
			(layers "B.Cu" "B.Mask" "B.Paste")
			(net "GND")
			(options
				(clearance outline)
				(anchor circle)
			)
			(primitives
				(gr_poly
					(pts
						(arc
							(start 0.1524 0.127)
							(mid 0.137521 0.162921)
							(end 0.1016 0.1778)
						)
						(arc
							(start -0.1016 0.1778)
							(mid -0.137521 0.162921)
							(end -0.1524 0.127)
						)
						(arc
							(start -0.1524 -0.127)
							(mid -0.137521 -0.162921)
							(end -0.1016 -0.1778)
						)
						(arc
							(start 0.1016 -0.1778)
							(mid 0.137521 -0.162921)
							(end 0.1524 -0.127)
						)
					)
					(width 0)
					(fill yes)
				)
			)
		)
	)
	(footprint ""
		(layer "B.Cu")
		(at 186.3344 -30.607 90)
		(property "Reference" "TP80"
			(at 0 0 90)
			(layer "B.SilkS")
			(hide yes)
			(effects
				(font
					(size 1.27 1.27)
				)
				(justify mirror)
			)
		)
		(property "Value" "TPAD28-2-GP"
			(at 0.0127 -1.6637 90)
			(unlocked yes)
			(layer "B.Fab")
			(hide yes)
			(effects
				(font
					(size 1.016 1.016)
					(thickness 0.1524)
				)
				(justify mirror)
			)
		)
		(property "Device Type" "TPAD28"
			(at 0.0127 -3.1877 90)
			(unlocked yes)
			(layer "B.Fab")
			(hide yes)
			(effects
				(font
					(size 1.016 1.016)
					(thickness 0.1524)
				)
				(justify mirror)
			)
		)
		(duplicate_pad_numbers_are_jumpers no)
		(fp_poly
			(pts
				(arc
					(start 0 0.3556)
					(mid 0 -0.3556)
					(end 0 0.3556)
				)
			)
			(stroke
				(width 0)
				(type default)
			)
			(fill no)
			(layer "B.CrtYd")
		)
		(fp_poly
			(pts
				(arc
					(start 0 0.6096)
					(mid 0 -0.6096)
					(end 0 0.6096)
				)
			)
			(stroke
				(width 0)
				(type default)
			)
			(fill no)
			(layer "B.Fab")
		)
		(pad "1" smd circle
			(at 0 0 270)
			(size 0.7112 0.7112)
			(layers "B.Cu" "B.Mask" "B.Paste")
			(net "IOC_GPIO_26")
		)
	)
	(footprint ""
		(layer "B.Cu")
		(at 107.8738 -44.2214 180)
		(property "Reference" "C72"
			(at 0 0 0)
			(layer "B.SilkS")
			(hide yes)
			(effects
				(font
					(size 1.27 1.27)
				)
				(justify mirror)
			)
		)
		(property "Value" "SCD01U16V1KX-GP"
			(at 2.8321 -1.7399 180)
			(unlocked yes)
			(layer "B.Fab")
			(hide yes)
			(effects
				(font
					(size 1.016 1.016)
					(thickness 0.1524)
				)
				(justify mirror)
			)
		)
		(property "Device Type" "C0201H13"
			(at 2.8321 -3.2639 180)
			(unlocked yes)
			(layer "B.Fab")
			(hide yes)
			(effects
				(font
					(size 1.016 1.016)
					(thickness 0.1524)
				)
				(justify mirror)
			)
		)
		(duplicate_pad_numbers_are_jumpers no)
		(fp_rect
			(start 0.2794 0.6477)
			(end -0.2794 -0.6477)
			(stroke
				(width 0)
				(type default)
			)
			(fill no)
			(layer "B.CrtYd")
		)
		(fp_rect
			(start 0.2794 0.6477)
			(end -0.2794 -0.6477)
			(stroke
				(width 0)
				(type default)
			)
			(fill no)
			(layer "B.Fab")
		)
		(pad "1" smd custom
			(at 0 -0.2794)
			(size 0.0762 0.0762)
			(layers "B.Cu" "B.Mask" "B.Paste")
			(net "PHY_DPB_TO_SCC_23_DP")
			(options
				(clearance outline)
				(anchor circle)
			)
			(primitives
				(gr_poly
					(pts
						(arc
							(start 0.1524 0.127)
							(mid 0.137521 0.162921)
							(end 0.1016 0.1778)
						)
						(arc
							(start -0.1016 0.1778)
							(mid -0.137521 0.162921)
							(end -0.1524 0.127)
						)
						(arc
							(start -0.1524 -0.127)
							(mid -0.137521 -0.162921)
							(end -0.1016 -0.1778)
						)
						(arc
							(start 0.1016 -0.1778)
							(mid 0.137521 -0.162921)
							(end 0.1524 -0.127)
						)
					)
					(width 0)
					(fill yes)
				)
			)
		)
		(pad "2" smd custom
			(at 0 0.2794)
			(size 0.0762 0.0762)
			(layers "B.Cu" "B.Mask" "B.Paste")
			(net "PHY_DPB_TO_SCC_C_23_DP")
			(options
				(clearance outline)
				(anchor circle)
			)
			(primitives
				(gr_poly
					(pts
						(arc
							(start 0.1524 0.127)
							(mid 0.137521 0.162921)
							(end 0.1016 0.1778)
						)
						(arc
							(start -0.1016 0.1778)
							(mid -0.137521 0.162921)
							(end -0.1524 0.127)
						)
						(arc
							(start -0.1524 -0.127)
							(mid -0.137521 -0.162921)
							(end -0.1016 -0.1778)
						)
						(arc
							(start 0.1016 -0.1778)
							(mid 0.137521 -0.162921)
							(end 0.1524 -0.127)
						)
					)
					(width 0)
					(fill yes)
				)
			)
		)
	)
	(footprint ""
		(layer "B.Cu")
		(at 86.4616 -72.5932 -90)
		(property "Reference" "C116"
			(at 0 0 90)
			(layer "B.SilkS")
			(hide yes)
			(effects
				(font
					(size 1.27 1.27)
				)
				(justify mirror)
			)
		)
		(property "Value" "SCD1U16V2KX-3GP"
			(at -1.1811 -2.7051 270)
			(unlocked yes)
			(layer "B.Fab")
			(hide yes)
			(effects
				(font
					(size 1.016 1.016)
					(thickness 0.1524)
				)
				(justify mirror)
			)
		)
		(property "Device Type" "C402H22"
			(at -1.1811 -4.2291 270)
			(unlocked yes)
			(layer "B.Fab")
			(hide yes)
			(effects
				(font
					(size 1.016 1.016)
					(thickness 0.1524)
				)
				(justify mirror)
			)
		)
		(duplicate_pad_numbers_are_jumpers no)
		(fp_rect
			(start 0.4318 0.9525)
			(end -0.4318 -0.9525)
			(stroke
				(width 0)
				(type default)
			)
			(fill no)
			(layer "B.CrtYd")
		)
		(fp_rect
			(start 0.4318 0.9525)
			(end -0.4318 -0.9525)
			(stroke
				(width 0)
				(type default)
			)
			(fill no)
			(layer "B.Fab")
		)
		(pad "1" smd custom
			(at 0 -0.4445 90)
			(size 0.1524 0.1524)
			(layers "B.Cu" "B.Mask" "B.Paste")
			(net "P1V8_E")
			(options
				(clearance outline)
				(anchor circle)
			)
			(primitives
				(gr_poly
					(pts
						(arc
							(start 0.3048 0.2032)
							(mid 0.275042 0.275042)
							(end 0.2032 0.3048)
						)
						(arc
							(start -0.2032 0.3048)
							(mid -0.275042 0.275042)
							(end -0.3048 0.2032)
						)
						(arc
							(start -0.3048 -0.2032)
							(mid -0.275042 -0.275042)
							(end -0.2032 -0.3048)
						)
						(arc
							(start 0.2032 -0.3048)
							(mid 0.275042 -0.275042)
							(end 0.3048 -0.2032)
						)
					)
					(width 0)
					(fill yes)
				)
			)
		)
		(pad "2" smd custom
			(at 0 0.4445 90)
			(size 0.1524 0.1524)
			(layers "B.Cu" "B.Mask" "B.Paste")
			(net "GND")
			(options
				(clearance outline)
				(anchor circle)
			)
			(primitives
				(gr_poly
					(pts
						(arc
							(start 0.3048 0.2032)
							(mid 0.275042 0.275042)
							(end 0.2032 0.3048)
						)
						(arc
							(start -0.2032 0.3048)
							(mid -0.275042 0.275042)
							(end -0.3048 0.2032)
						)
						(arc
							(start -0.3048 -0.2032)
							(mid -0.275042 -0.275042)
							(end -0.2032 -0.3048)
						)
						(arc
							(start 0.2032 -0.3048)
							(mid 0.275042 -0.275042)
							(end 0.3048 -0.2032)
						)
					)
					(width 0)
					(fill yes)
				)
			)
		)
	)
	(footprint ""
		(layer "B.Cu")
		(at 70.485 -58.674 90)
		(property "Reference" "L10"
			(at 0 0 90)
			(layer "B.SilkS")
			(hide yes)
			(effects
				(font
					(size 1.27 1.27)
				)
				(justify mirror)
			)
		)
		(property "Value" "MPZ2012S300AT-GP"
			(at 0 -4.2418 90)
			(unlocked yes)
			(layer "B.Fab")
			(hide yes)
			(effects
				(font
					(size 1.016 1.016)
					(thickness 0.1524)
				)
				(justify mirror)
			)
		)
		(property "Device Type" "L805H42"
			(at 0 -5.7912 90)
			(unlocked yes)
			(layer "B.Fab")
			(hide yes)
			(effects
				(font
					(size 1.016 1.016)
					(thickness 0.1524)
				)
				(justify mirror)
			)
		)
		(duplicate_pad_numbers_are_jumpers no)
		(fp_line
			(start 0.889 -1.7018)
			(end -0.889 -1.7018)
			(stroke
				(width 0.1524)
				(type default)
			)
			(layer "B.SilkS")
		)
		(fp_line
			(start -0.889 -1.7018)
			(end -0.889 1.7018)
			(stroke
				(width 0.1524)
				(type default)
			)
			(layer "B.SilkS")
		)
		(fp_line
			(start 0.889 1.7018)
			(end 0.889 -1.7018)
			(stroke
				(width 0.1524)
				(type default)
			)
			(layer "B.SilkS")
		)
		(fp_line
			(start -0.889 1.7018)
			(end 0.889 1.7018)
			(stroke
				(width 0.1524)
				(type default)
			)
			(layer "B.SilkS")
		)
		(fp_rect
			(start 0.9652 1.778)
			(end -0.9652 -1.778)
			(stroke
				(width 0)
				(type default)
			)
			(fill no)
			(layer "B.CrtYd")
		)
		(fp_rect
			(start 0.9652 1.778)
			(end -0.9652 -1.778)
			(stroke
				(width 0)
				(type default)
			)
			(fill no)
			(layer "B.Fab")
		)
		(pad "1" smd rect
			(at 0 -0.9652 270)
			(size 1.397 1.143)
			(layers "B.Cu" "B.Mask" "B.Paste")
			(net "P0V9")
		)
		(pad "2" smd rect
			(at 0 0.9652 270)
			(size 1.397 1.143)
			(layers "B.Cu" "B.Mask" "B.Paste")
			(net "GB_VDDA")
		)
	)
	(footprint ""
		(layer "B.Cu")
		(at 164.723318 -30.381956 -90)
		(property "Reference" "C399"
			(at 0 0 90)
			(layer "B.SilkS")
			(hide yes)
			(effects
				(font
					(size 1.27 1.27)
				)
				(justify mirror)
			)
		)
		(property "Value" "SCD1U16V2KX-3GP"
			(at -1.1811 -2.7051 270)
			(unlocked yes)
			(layer "B.Fab")
			(hide yes)
			(effects
				(font
					(size 1.016 1.016)
					(thickness 0.1524)
				)
				(justify mirror)
			)
		)
		(property "Device Type" "C402H22"
			(at -1.1811 -4.2291 270)
			(unlocked yes)
			(layer "B.Fab")
			(hide yes)
			(effects
				(font
					(size 1.016 1.016)
					(thickness 0.1524)
				)
				(justify mirror)
			)
		)
		(duplicate_pad_numbers_are_jumpers no)
		(fp_rect
			(start 0.4318 0.9525)
			(end -0.4318 -0.9525)
			(stroke
				(width 0)
				(type default)
			)
			(fill no)
			(layer "B.CrtYd")
		)
		(fp_rect
			(start 0.4318 0.9525)
			(end -0.4318 -0.9525)
			(stroke
				(width 0)
				(type default)
			)
			(fill no)
			(layer "B.Fab")
		)
		(pad "1" smd custom
			(at 0 -0.4445 90)
			(size 0.1524 0.1524)
			(layers "B.Cu" "B.Mask" "B.Paste")
			(net "SAS0_AVDD")
			(options
				(clearance outline)
				(anchor circle)
			)
			(primitives
				(gr_poly
					(pts
						(arc
							(start 0.3048 0.2032)
							(mid 0.275042 0.275042)
							(end 0.2032 0.3048)
						)
						(arc
							(start -0.2032 0.3048)
							(mid -0.275042 0.275042)
							(end -0.3048 0.2032)
						)
						(arc
							(start -0.3048 -0.2032)
							(mid -0.275042 -0.275042)
							(end -0.2032 -0.3048)
						)
						(arc
							(start 0.2032 -0.3048)
							(mid 0.275042 -0.275042)
							(end 0.3048 -0.2032)
						)
					)
					(width 0)
					(fill yes)
				)
			)
		)
		(pad "2" smd custom
			(at 0 0.4445 90)
			(size 0.1524 0.1524)
			(layers "B.Cu" "B.Mask" "B.Paste")
			(net "GND")
			(options
				(clearance outline)
				(anchor circle)
			)
			(primitives
				(gr_poly
					(pts
						(arc
							(start 0.3048 0.2032)
							(mid 0.275042 0.275042)
							(end 0.2032 0.3048)
						)
						(arc
							(start -0.2032 0.3048)
							(mid -0.275042 0.275042)
							(end -0.3048 0.2032)
						)
						(arc
							(start -0.3048 -0.2032)
							(mid -0.275042 -0.275042)
							(end -0.2032 -0.3048)
						)
						(arc
							(start 0.2032 -0.3048)
							(mid 0.275042 -0.275042)
							(end 0.3048 -0.2032)
						)
					)
					(width 0)
					(fill yes)
				)
			)
		)
	)
	(footprint ""
		(layer "B.Cu")
		(at 71.5518 -14.558772 180)
		(property "Reference" "C98"
			(at 0 0 0)
			(layer "B.SilkS")
			(hide yes)
			(effects
				(font
					(size 1.27 1.27)
				)
				(justify mirror)
			)
		)
		(property "Value" "SCD1U16V2KX-3GP"
			(at -1.1811 -2.7051 180)
			(unlocked yes)
			(layer "B.Fab")
			(hide yes)
			(effects
				(font
					(size 1.016 1.016)
					(thickness 0.1524)
				)
				(justify mirror)
			)
		)
		(property "Device Type" "C402H22"
			(at -1.1811 -4.2291 180)
			(unlocked yes)
			(layer "B.Fab")
			(hide yes)
			(effects
				(font
					(size 1.016 1.016)
					(thickness 0.1524)
				)
				(justify mirror)
			)
		)
		(duplicate_pad_numbers_are_jumpers no)
		(fp_rect
			(start 0.4318 0.9525)
			(end -0.4318 -0.9525)
			(stroke
				(width 0)
				(type default)
			)
			(fill no)
			(layer "B.CrtYd")
		)
		(fp_rect
			(start 0.4318 0.9525)
			(end -0.4318 -0.9525)
			(stroke
				(width 0)
				(type default)
			)
			(fill no)
			(layer "B.Fab")
		)
		(pad "1" smd custom
			(at 0 -0.4445)
			(size 0.1524 0.1524)
			(layers "B.Cu" "B.Mask" "B.Paste")
			(net "P3V3")
			(options
				(clearance outline)
				(anchor circle)
			)
			(primitives
				(gr_poly
					(pts
						(arc
							(start 0.3048 0.2032)
							(mid 0.275042 0.275042)
							(end 0.2032 0.3048)
						)
						(arc
							(start -0.2032 0.3048)
							(mid -0.275042 0.275042)
							(end -0.3048 0.2032)
						)
						(arc
							(start -0.3048 -0.2032)
							(mid -0.275042 -0.275042)
							(end -0.2032 -0.3048)
						)
						(arc
							(start 0.2032 -0.3048)
							(mid 0.275042 -0.275042)
							(end 0.3048 -0.2032)
						)
					)
					(width 0)
					(fill yes)
				)
			)
		)
		(pad "2" smd custom
			(at 0 0.4445)
			(size 0.1524 0.1524)
			(layers "B.Cu" "B.Mask" "B.Paste")
			(net "GND")
			(options
				(clearance outline)
				(anchor circle)
			)
			(primitives
				(gr_poly
					(pts
						(arc
							(start 0.3048 0.2032)
							(mid 0.275042 0.275042)
							(end 0.2032 0.3048)
						)
						(arc
							(start -0.2032 0.3048)
							(mid -0.275042 0.275042)
							(end -0.3048 0.2032)
						)
						(arc
							(start -0.3048 -0.2032)
							(mid -0.275042 -0.275042)
							(end -0.2032 -0.3048)
						)
						(arc
							(start 0.2032 -0.3048)
							(mid 0.275042 -0.275042)
							(end 0.3048 -0.2032)
						)
					)
					(width 0)
					(fill yes)
				)
			)
		)
	)
)
